# S9S_MB_2U (Grand Teton) — schematic netlist excerpt (pin names and nets, part order shuffled) for the footprints in the layout excerpt that follows; sources: Cadence DE-HDL packaged netlist, KiCad conversion of 03242023_DA0F0TMBIJ0_F0T_Motherboard_J_brd_V01_OCP.brd

R652  Q_RES  2.2K 5% CHIP  pkg 0402LF  page 231 : A = P3V3_AUX ; B = SMB_FRU_3V3AUX_SDA
C1567  Q_CAP_DIFFBUS  DIFF BUS_0.22UF 6.3V 20% X6S  pkg C0201  page 175 : \1\ = P5E_CPU0_PE4_TX_C_DP<6> ; \2\ = P5E_CPU0_PE4_TX_DP<6>
PR203  Q_RES  24.3K 1% CHIP  pkg 0402LF  page 296 : A = GND ; B = PVCCD_HV_CPU1_ADDR

(kicad_pcb
	(version 20260206)
	(generator "pcbnew")
	(generator_version "10.0")
	(general
		(thickness 1.6)
		(legacy_teardrops no)
	)
	(paper "A4")
	(title_block
		(title "03242023_DA0F0TMBIJ0_F0T_Motherboard_J_brd_V01_OCP.brd")
		(comment 1 "Grand Teton / footprints 2306-2308 of 6105")
	)
	(layers
		(0 "F.Cu" signal "TOP")
		(4 "In1.Cu" signal "GND")
		(6 "In2.Cu" signal "IN1")
		(8 "In3.Cu" signal "GND1")
		(10 "In4.Cu" signal "IN2")
		(12 "In5.Cu" signal "GND2")
		(14 "In6.Cu" signal "IN3")
		(16 "In7.Cu" signal "GND3")
		(18 "In8.Cu" signal "VCC")
		(20 "In9.Cu" signal "VCC1")
		(22 "In10.Cu" signal "GND4")
		(24 "In11.Cu" signal "IN4")
		(26 "In12.Cu" signal "GND5")
		(28 "In13.Cu" signal "IN5")
		(30 "In14.Cu" signal "GND6")
		(32 "In15.Cu" signal "IN6")
		(34 "In16.Cu" signal "GND7")
		(2 "B.Cu" signal "BOTTOM")
		(9 "F.Adhes" user "F.Adhesive")
		(11 "B.Adhes" user "B.Adhesive")
		(13 "F.Paste" user "Package Geometry/Pastemask Top")
		(15 "B.Paste" user "Package Geometry/Pastemask Bottom")
		(5 "F.SilkS" user "Ref Des/Silkscreen Top")
		(7 "B.SilkS" user "Ref Des/Silkscreen Bottom")
		(1 "F.Mask" user "Board Geometry/Soldermask Top")
		(3 "B.Mask" user "Board Geometry/Soldermask Bottom")
		(17 "Dwgs.User" user "User.Drawings")
		(19 "Cmts.User" user "User.Comments")
		(21 "Eco1.User" user "User.Eco1")
		(23 "Eco2.User" user "User.Eco2")
		(25 "Edge.Cuts" user "Board Geometry/Outline")
		(27 "Margin" user)
		(31 "F.CrtYd" user "Package Geometry/Place Bound Top")
		(29 "B.CrtYd" user "Package Geometry/Place Bound Bottom")
		(35 "F.Fab" user "Ref Des/Assembly Top")
		(33 "B.Fab" user "Ref Des/Assembly Bottom")
	)
	(footprint ""
		(layer "F.Cu")
		(at 31.937452 -161.582862 180)
		(property "Reference" "PR203"
			(at 0 0 180)
			(layer "F.SilkS")
			(hide yes)
			(effects
				(font
					(size 1.27 1.27)
				)
			)
		)
		(property "Value" ""
			(at 0 0 180)
			(layer "F.Fab")
			(effects
				(font
					(size 1.27 1.27)
				)
			)
		)
		(duplicate_pad_numbers_are_jumpers no)
		(fp_line
			(start 0.7874 0.4064)
			(end -0.7874 0.4064)
			(stroke
				(width 0.1524)
				(type default)
			)
			(layer "F.SilkS")
		)
		(fp_line
			(start 0.7874 -0.4064)
			(end 0.7874 0.4064)
			(stroke
				(width 0.1524)
				(type default)
			)
			(layer "F.SilkS")
		)
		(fp_line
			(start -0.7874 0.4064)
			(end -0.7874 -0.4064)
			(stroke
				(width 0.1524)
				(type default)
			)
			(layer "F.SilkS")
		)
		(fp_line
			(start -0.7874 -0.4064)
			(end 0.7874 -0.4064)
			(stroke
				(width 0.1524)
				(type default)
			)
			(layer "F.SilkS")
		)
		(fp_line
			(start 0.67945 0.3048)
			(end 0.120396 0.3048)
			(stroke
				(width 0.1)
				(type default)
			)
			(layer "F.Fab")
		)
		(fp_line
			(start 0.67945 -0.3048)
			(end 0.67945 0.3048)
			(stroke
				(width 0.1)
				(type default)
			)
			(layer "F.Fab")
		)
		(fp_line
			(start 0.12065 -0.2794)
			(end 0.12065 -0.3048)
			(stroke
				(width 0.1)
				(type default)
			)
			(layer "F.Fab")
		)
		(fp_line
			(start 0.12065 -0.3048)
			(end 0.67945 -0.3048)
			(stroke
				(width 0.1)
				(type default)
			)
			(layer "F.Fab")
		)
		(fp_line
			(start 0.120396 0.3048)
			(end 0.120396 0.2794)
			(stroke
				(width 0.1)
				(type default)
			)
			(layer "F.Fab")
		)
		(fp_line
			(start 0.120396 0.2794)
			(end -0.12065 0.2794)
			(stroke
				(width 0.1)
				(type default)
			)
			(layer "F.Fab")
		)
		(fp_line
			(start -0.12065 0.3048)
			(end -0.67945 0.3048)
			(stroke
				(width 0.1)
				(type default)
			)
			(layer "F.Fab")
		)
		(fp_line
			(start -0.12065 0.2794)
			(end -0.12065 0.3048)
			(stroke
				(width 0.1)
				(type default)
			)
			(layer "F.Fab")
		)
		(fp_line
			(start -0.12065 -0.2794)
			(end 0.12065 -0.2794)
			(stroke
				(width 0.1)
				(type default)
			)
			(layer "F.Fab")
		)
		(fp_line
			(start -0.12065 -0.305054)
			(end -0.12065 -0.2794)
			(stroke
				(width 0.1)
				(type default)
			)
			(layer "F.Fab")
		)
		(fp_line
			(start -0.67945 0.3048)
			(end -0.67945 -0.305054)
			(stroke
				(width 0.1)
				(type default)
			)
			(layer "F.Fab")
		)
		(fp_line
			(start -0.67945 -0.305054)
			(end -0.12065 -0.305054)
			(stroke
				(width 0.1)
				(type default)
			)
			(layer "F.Fab")
		)
		(pad "1" smd circle
			(at -0.40005 0 180)
			(size 0 0)
			(layers "F.Cu" "F.Mask" "F.Paste")
			(net "GND")
		)
		(pad "2" smd circle
			(at 0.40005 0 180)
			(size 0 0)
			(layers "F.Cu" "F.Mask" "F.Paste")
			(net "PVCCD_HV_CPU1_ADDR")
		)
	)
	(footprint ""
		(layer "F.Cu")
		(at 323.248528 -402.371052 -90)
		(property "Reference" "C1567"
			(at 0 0 270)
			(layer "F.SilkS")
			(hide yes)
			(effects
				(font
					(size 1.27 1.27)
				)
			)
		)
		(property "Value" ""
			(at 0 0 270)
			(layer "F.Fab")
			(effects
				(font
					(size 1.27 1.27)
				)
			)
		)
		(duplicate_pad_numbers_are_jumpers no)
		(fp_line
			(start -0.299974 0.150114)
			(end -0.299974 -0.150114)
			(stroke
				(width 0.1)
				(type default)
			)
			(layer "F.Fab")
		)
		(fp_line
			(start 0.299974 0.150114)
			(end -0.299974 0.150114)
			(stroke
				(width 0.1)
				(type default)
			)
			(layer "F.Fab")
		)
		(fp_line
			(start -0.299974 -0.150114)
			(end 0.299974 -0.150114)
			(stroke
				(width 0.1)
				(type default)
			)
			(layer "F.Fab")
		)
		(fp_line
			(start 0.299974 -0.150114)
			(end 0.299974 0.150114)
			(stroke
				(width 0.1)
				(type default)
			)
			(layer "F.Fab")
		)
		(pad "1" smd rect
			(at -0.2667 0 270)
			(size 0.3048 0.381)
			(layers "F.Cu" "F.Mask" "F.Paste")
			(net "P5E_CPU0_PE4_TX_C_DP<6>")
		)
		(pad "2" smd rect
			(at 0.2667 0 270)
			(size 0.3048 0.381)
			(layers "F.Cu" "F.Mask" "F.Paste")
			(net "P5E_CPU0_PE4_TX_DP<6>")
		)
	)
	(footprint ""
		(layer "F.Cu")
		(at 131.466844 -129.913126 180)
		(property "Reference" "R652"
			(at 0 0 180)
			(layer "F.SilkS")
			(hide yes)
			(effects
				(font
					(size 1.27 1.27)
				)
			)
		)
		(property "Value" ""
			(at 0 0 180)
			(layer "F.Fab")
			(effects
				(font
					(size 1.27 1.27)
				)
			)
		)
		(duplicate_pad_numbers_are_jumpers no)
		(fp_line
			(start 0.7874 0.4064)
			(end -0.7874 0.4064)
			(stroke
				(width 0.1524)
				(type default)
			)
			(layer "F.SilkS")
		)
		(fp_line
			(start 0.7874 -0.4064)
			(end 0.7874 0.4064)
			(stroke
				(width 0.1524)
				(type default)
			)
			(layer "F.SilkS")
		)
		(fp_line
			(start -0.7874 0.4064)
			(end -0.7874 -0.4064)
			(stroke
				(width 0.1524)
				(type default)
			)
			(layer "F.SilkS")
		)
		(fp_line
			(start -0.7874 -0.4064)
			(end 0.7874 -0.4064)
			(stroke
				(width 0.1524)
				(type default)
			)
			(layer "F.SilkS")
		)
		(fp_line
			(start 0.67945 0.3048)
			(end 0.120396 0.3048)
			(stroke
				(width 0.1)
				(type default)
			)
			(layer "F.Fab")
		)
		(fp_line
			(start 0.67945 -0.3048)
			(end 0.67945 0.3048)
			(stroke
				(width 0.1)
				(type default)
			)
			(layer "F.Fab")
		)
		(fp_line
			(start 0.12065 -0.2794)
			(end 0.12065 -0.3048)
			(stroke
				(width 0.1)
				(type default)
			)
			(layer "F.Fab")
		)
		(fp_line
			(start 0.12065 -0.3048)
			(end 0.67945 -0.3048)
			(stroke
				(width 0.1)
				(type default)
			)
			(layer "F.Fab")
		)
		(fp_line
			(start 0.120396 0.3048)
			(end 0.120396 0.2794)
			(stroke
				(width 0.1)
				(type default)
			)
			(layer "F.Fab")
		)
		(fp_line
			(start 0.120396 0.2794)
			(end -0.12065 0.2794)
			(stroke
				(width 0.1)
				(type default)
			)
			(layer "F.Fab")
		)
		(fp_line
			(start -0.12065 0.3048)
			(end -0.67945 0.3048)
			(stroke
				(width 0.1)
				(type default)
			)
			(layer "F.Fab")
		)
		(fp_line
			(start -0.12065 0.2794)
			(end -0.12065 0.3048)
			(stroke
				(width 0.1)
				(type default)
			)
			(layer "F.Fab")
		)
		(fp_line
			(start -0.12065 -0.2794)
			(end 0.12065 -0.2794)
			(stroke
				(width 0.1)
				(type default)
			)
			(layer "F.Fab")
		)
		(fp_line
			(start -0.12065 -0.305054)
			(end -0.12065 -0.2794)
			(stroke
				(width 0.1)
				(type default)
			)
			(layer "F.Fab")
		)
		(fp_line
			(start -0.67945 0.3048)
			(end -0.67945 -0.305054)
			(stroke
				(width 0.1)
				(type default)
			)
			(layer "F.Fab")
		)
		(fp_line
			(start -0.67945 -0.305054)
			(end -0.12065 -0.305054)
			(stroke
				(width 0.1)
				(type default)
			)
			(layer "F.Fab")
		)
		(pad "1" smd circle
			(at -0.40005 0 180)
			(size 0 0)
			(layers "F.Cu" "F.Mask" "F.Paste")
			(net "P3V3_AUX")
		)
		(pad "2" smd circle
			(at 0.40005 0 180)
			(size 0 0)
			(layers "F.Cu" "F.Mask" "F.Paste")
			(net "SMB_FRU_3V3AUX_SDA")
		)
	)
)
